(kicad_pcb
	(version 20260206)
	(generator "pcbnew")
	(generator_version "10.0")
	(general
		(thickness 1.6)
		(legacy_teardrops no)
	)
	(paper "A4")
	(title_block
		(title "04192023_DAF0TMB3IC0_F0TG_MB_C_brd_V02_OCP.brd")
		(comment 1 "Grand Teton / footprints 7123-7129 of 8354")
	)
	(layers
		(0 "F.Cu" signal "TOP")
		(4 "In1.Cu" signal "GND")
		(6 "In2.Cu" signal "IN1")
		(8 "In3.Cu" signal "GND1")
		(10 "In4.Cu" signal "IN2")
		(12 "In5.Cu" signal "GND2")
		(14 "In6.Cu" signal "IN3")
		(16 "In7.Cu" signal "GND3")
		(18 "In8.Cu" signal "VCC")
		(20 "In9.Cu" signal "VCC1")
		(22 "In10.Cu" signal "GND4")
		(24 "In11.Cu" signal "IN4")
		(26 "In12.Cu" signal "GND5")
		(28 "In13.Cu" signal "IN5")
		(30 "In14.Cu" signal "GND6")
		(32 "In15.Cu" signal "IN6")
		(34 "In16.Cu" signal "GND7")
		(2 "B.Cu" signal "BOTTOM")
		(9 "F.Adhes" user "F.Adhesive")
		(11 "B.Adhes" user "B.Adhesive")
		(13 "F.Paste" user "Package Geometry/Pastemask Top")
		(15 "B.Paste" user "Package Geometry/Pastemask Bottom")
		(5 "F.SilkS" user "Ref Des/Silkscreen Top")
		(7 "B.SilkS" user "Ref Des/Silkscreen Bottom")
		(1 "F.Mask" user "Board Geometry/Soldermask Top")
		(3 "B.Mask" user "Board Geometry/Soldermask Bottom")
		(17 "Dwgs.User" user "User.Drawings")
		(19 "Cmts.User" user "User.Comments")
		(21 "Eco1.User" user "User.Eco1")
		(23 "Eco2.User" user "User.Eco2")
		(25 "Edge.Cuts" user "Board Geometry/Outline")
		(27 "Margin" user)
		(31 "F.CrtYd" user "Package Geometry/Place Bound Top")
		(29 "B.CrtYd" user "Package Geometry/Place Bound Bottom")
		(35 "F.Fab" user "Ref Des/Assembly Top")
		(33 "B.Fab" user "Ref Des/Assembly Bottom")
	)
	(footprint ""
		(layer "B.Cu")
		(at 283.980636 -194.893946 180)
		(property "Reference" "R1"
			(at 0 0 0)
			(layer "B.SilkS")
			(hide yes)
			(effects
				(font
					(size 1.27 1.27)
				)
				(justify mirror)
			)
		)
		(property "Value" ""
			(at 0 0 0)
			(layer "B.Fab")
			(effects
				(font
					(size 1.27 1.27)
				)
				(justify mirror)
			)
		)
		(duplicate_pad_numbers_are_jumpers no)
		(fp_line
			(start 0.7874 0.4064)
			(end 0.7874 -0.4064)
			(stroke
				(width 0.1524)
				(type default)
			)
			(layer "B.SilkS")
		)
		(fp_line
			(start 0.7874 -0.4064)
			(end -0.7874 -0.4064)
			(stroke
				(width 0.1524)
				(type default)
			)
			(layer "B.SilkS")
		)
		(fp_line
			(start -0.7874 0.4064)
			(end 0.7874 0.4064)
			(stroke
				(width 0.1524)
				(type default)
			)
			(layer "B.SilkS")
		)
		(fp_line
			(start -0.7874 -0.4064)
			(end -0.7874 0.4064)
			(stroke
				(width 0.1524)
				(type default)
			)
			(layer "B.SilkS")
		)
		(fp_line
			(start 0.67945 0.3048)
			(end 0.67945 -0.305054)
			(stroke
				(width 0.1)
				(type default)
			)
			(layer "B.Fab")
		)
		(fp_line
			(start 0.67945 -0.305054)
			(end 0.12065 -0.305054)
			(stroke
				(width 0.1)
				(type default)
			)
			(layer "B.Fab")
		)
		(fp_line
			(start 0.12065 0.3048)
			(end 0.67945 0.3048)
			(stroke
				(width 0.1)
				(type default)
			)
			(layer "B.Fab")
		)
		(fp_line
			(start 0.12065 0.2794)
			(end 0.12065 0.3048)
			(stroke
				(width 0.1)
				(type default)
			)
			(layer "B.Fab")
		)
		(fp_line
			(start 0.12065 -0.2794)
			(end -0.12065 -0.2794)
			(stroke
				(width 0.1)
				(type default)
			)
			(layer "B.Fab")
		)
		(fp_line
			(start 0.12065 -0.305054)
			(end 0.12065 -0.2794)
			(stroke
				(width 0.1)
				(type default)
			)
			(layer "B.Fab")
		)
		(fp_line
			(start -0.120396 0.3048)
			(end -0.120396 0.2794)
			(stroke
				(width 0.1)
				(type default)
			)
			(layer "B.Fab")
		)
		(fp_line
			(start -0.120396 0.2794)
			(end 0.12065 0.2794)
			(stroke
				(width 0.1)
				(type default)
			)
			(layer "B.Fab")
		)
		(fp_line
			(start -0.12065 -0.2794)
			(end -0.12065 -0.3048)
			(stroke
				(width 0.1)
				(type default)
			)
			(layer "B.Fab")
		)
		(fp_line
			(start -0.12065 -0.3048)
			(end -0.67945 -0.3048)
			(stroke
				(width 0.1)
				(type default)
			)
			(layer "B.Fab")
		)
		(fp_line
			(start -0.67945 0.3048)
			(end -0.120396 0.3048)
			(stroke
				(width 0.1)
				(type default)
			)
			(layer "B.Fab")
		)
		(fp_line
			(start -0.67945 -0.3048)
			(end -0.67945 0.3048)
			(stroke
				(width 0.1)
				(type default)
			)
			(layer "B.Fab")
		)
		(pad "1" smd circle
			(at 0.40005 0)
			(size 0 0)
			(layers "B.Cu" "B.Mask" "B.Paste")
			(net "I3C_SPD_DDRAF_CPU0_SCL")
		)
		(pad "2" smd circle
			(at -0.40005 0)
			(size 0 0)
			(layers "B.Cu" "B.Mask" "B.Paste")
			(net "I3C_SPD_DDRD_CPU0_SCL")
		)
	)
	(footprint ""
		(layer "B.Cu")
		(at 358.34447 -168.436798 90)
		(property "Reference" "PR352"
			(at 0 0 90)
			(layer "B.SilkS")
			(hide yes)
			(effects
				(font
					(size 1.27 1.27)
				)
				(justify mirror)
			)
		)
		(property "Value" ""
			(at 0 0 90)
			(layer "B.Fab")
			(effects
				(font
					(size 1.27 1.27)
				)
				(justify mirror)
			)
		)
		(duplicate_pad_numbers_are_jumpers no)
		(fp_line
			(start 0.7874 -0.4064)
			(end -0.7874 -0.4064)
			(stroke
				(width 0.1524)
				(type default)
			)
			(layer "B.SilkS")
		)
		(fp_line
			(start -0.7874 -0.4064)
			(end -0.7874 0.4064)
			(stroke
				(width 0.1524)
				(type default)
			)
			(layer "B.SilkS")
		)
		(fp_line
			(start 0.7874 0.4064)
			(end 0.7874 -0.4064)
			(stroke
				(width 0.1524)
				(type default)
			)
			(layer "B.SilkS")
		)
		(fp_line
			(start -0.7874 0.4064)
			(end 0.7874 0.4064)
			(stroke
				(width 0.1524)
				(type default)
			)
			(layer "B.SilkS")
		)
		(fp_line
			(start 0.67945 -0.305054)
			(end 0.12065 -0.305054)
			(stroke
				(width 0.1)
				(type default)
			)
			(layer "B.Fab")
		)
		(fp_line
			(start 0.12065 -0.305054)
			(end 0.12065 -0.2794)
			(stroke
				(width 0.1)
				(type default)
			)
			(layer "B.Fab")
		)
		(fp_line
			(start -0.12065 -0.3048)
			(end -0.67945 -0.3048)
			(stroke
				(width 0.1)
				(type default)
			)
			(layer "B.Fab")
		)
		(fp_line
			(start -0.67945 -0.3048)
			(end -0.67945 0.3048)
			(stroke
				(width 0.1)
				(type default)
			)
			(layer "B.Fab")
		)
		(fp_line
			(start 0.12065 -0.2794)
			(end -0.12065 -0.2794)
			(stroke
				(width 0.1)
				(type default)
			)
			(layer "B.Fab")
		)
		(fp_line
			(start -0.12065 -0.2794)
			(end -0.12065 -0.3048)
			(stroke
				(width 0.1)
				(type default)
			)
			(layer "B.Fab")
		)
		(fp_line
			(start 0.12065 0.2794)
			(end 0.12065 0.3048)
			(stroke
				(width 0.1)
				(type default)
			)
			(layer "B.Fab")
		)
		(fp_line
			(start -0.120396 0.2794)
			(end 0.12065 0.2794)
			(stroke
				(width 0.1)
				(type default)
			)
			(layer "B.Fab")
		)
		(fp_line
			(start 0.67945 0.3048)
			(end 0.67945 -0.305054)
			(stroke
				(width 0.1)
				(type default)
			)
			(layer "B.Fab")
		)
		(fp_line
			(start 0.12065 0.3048)
			(end 0.67945 0.3048)
			(stroke
				(width 0.1)
				(type default)
			)
			(layer "B.Fab")
		)
		(fp_line
			(start -0.120396 0.3048)
			(end -0.120396 0.2794)
			(stroke
				(width 0.1)
				(type default)
			)
			(layer "B.Fab")
		)
		(fp_line
			(start -0.67945 0.3048)
			(end -0.120396 0.3048)
			(stroke
				(width 0.1)
				(type default)
			)
			(layer "B.Fab")
		)
		(pad "1" smd circle
			(at 0.40005 0 270)
			(size 0 0)
			(layers "B.Cu" "B.Mask" "B.Paste")
			(net "PVDDCR_CPU0_P0_PVCC")
		)
		(pad "2" smd circle
			(at -0.40005 0 270)
			(size 0 0)
			(layers "B.Cu" "B.Mask" "B.Paste")
			(net "PVDDCR_CPU0_P0_VCC5")
		)
	)
	(footprint ""
		(layer "B.Cu")
		(at 164.957506 -16.44523 180)
		(property "Reference" "R2996"
			(at 0 0 0)
			(layer "B.SilkS")
			(hide yes)
			(effects
				(font
					(size 1.27 1.27)
				)
				(justify mirror)
			)
		)
		(property "Value" ""
			(at 0 0 0)
			(layer "B.Fab")
			(effects
				(font
					(size 1.27 1.27)
				)
				(justify mirror)
			)
		)
		(duplicate_pad_numbers_are_jumpers no)
		(fp_line
			(start 0.7874 0.4064)
			(end 0.7874 -0.4064)
			(stroke
				(width 0.1524)
				(type default)
			)
			(layer "B.SilkS")
		)
		(fp_line
			(start 0.7874 -0.4064)
			(end -0.7874 -0.4064)
			(stroke
				(width 0.1524)
				(type default)
			)
			(layer "B.SilkS")
		)
		(fp_line
			(start -0.7874 0.4064)
			(end 0.7874 0.4064)
			(stroke
				(width 0.1524)
				(type default)
			)
			(layer "B.SilkS")
		)
		(fp_line
			(start -0.7874 -0.4064)
			(end -0.7874 0.4064)
			(stroke
				(width 0.1524)
				(type default)
			)
			(layer "B.SilkS")
		)
		(fp_line
			(start 0.67945 0.3048)
			(end 0.67945 -0.305054)
			(stroke
				(width 0.1)
				(type default)
			)
			(layer "B.Fab")
		)
		(fp_line
			(start 0.67945 -0.305054)
			(end 0.12065 -0.305054)
			(stroke
				(width 0.1)
				(type default)
			)
			(layer "B.Fab")
		)
		(fp_line
			(start 0.12065 0.3048)
			(end 0.67945 0.3048)
			(stroke
				(width 0.1)
				(type default)
			)
			(layer "B.Fab")
		)
		(fp_line
			(start 0.12065 0.2794)
			(end 0.12065 0.3048)
			(stroke
				(width 0.1)
				(type default)
			)
			(layer "B.Fab")
		)
		(fp_line
			(start 0.12065 -0.2794)
			(end -0.12065 -0.2794)
			(stroke
				(width 0.1)
				(type default)
			)
			(layer "B.Fab")
		)
		(fp_line
			(start 0.12065 -0.305054)
			(end 0.12065 -0.2794)
			(stroke
				(width 0.1)
				(type default)
			)
			(layer "B.Fab")
		)
		(fp_line
			(start -0.120396 0.3048)
			(end -0.120396 0.2794)
			(stroke
				(width 0.1)
				(type default)
			)
			(layer "B.Fab")
		)
		(fp_line
			(start -0.120396 0.2794)
			(end 0.12065 0.2794)
			(stroke
				(width 0.1)
				(type default)
			)
			(layer "B.Fab")
		)
		(fp_line
			(start -0.12065 -0.2794)
			(end -0.12065 -0.3048)
			(stroke
				(width 0.1)
				(type default)
			)
			(layer "B.Fab")
		)
		(fp_line
			(start -0.12065 -0.3048)
			(end -0.67945 -0.3048)
			(stroke
				(width 0.1)
				(type default)
			)
			(layer "B.Fab")
		)
		(fp_line
			(start -0.67945 0.3048)
			(end -0.120396 0.3048)
			(stroke
				(width 0.1)
				(type default)
			)
			(layer "B.Fab")
		)
		(fp_line
			(start -0.67945 -0.3048)
			(end -0.67945 0.3048)
			(stroke
				(width 0.1)
				(type default)
			)
			(layer "B.Fab")
		)
		(pad "1" smd circle
			(at 0.40005 0)
			(size 0 0)
			(layers "B.Cu" "B.Mask" "B.Paste")
			(net "SMB_PMBUS_3V3AUX_SDA")
		)
		(pad "2" smd circle
			(at -0.40005 0)
			(size 0 0)
			(layers "B.Cu" "B.Mask" "B.Paste")
			(net "SMB_SML1_PMBUS_HSC_SDA")
		)
	)
	(footprint ""
		(layer "B.Cu")
		(at 114.272822 -385.50088 -90)
		(property "Reference" "C459"
			(at 0 0 90)
			(layer "B.SilkS")
			(hide yes)
			(effects
				(font
					(size 1.27 1.27)
				)
				(justify mirror)
			)
		)
		(property "Value" ""
			(at 0 0 90)
			(layer "B.Fab")
			(effects
				(font
					(size 1.27 1.27)
				)
				(justify mirror)
			)
		)
		(duplicate_pad_numbers_are_jumpers no)
		(fp_line
			(start -0.299974 0.150114)
			(end 0.299974 0.150114)
			(stroke
				(width 0.1)
				(type default)
			)
			(layer "B.Fab")
		)
		(fp_line
			(start 0.299974 0.150114)
			(end 0.299974 -0.150114)
			(stroke
				(width 0.1)
				(type default)
			)
			(layer "B.Fab")
		)
		(fp_line
			(start -0.299974 -0.150114)
			(end -0.299974 0.150114)
			(stroke
				(width 0.1)
				(type default)
			)
			(layer "B.Fab")
		)
		(fp_line
			(start 0.299974 -0.150114)
			(end -0.299974 -0.150114)
			(stroke
				(width 0.1)
				(type default)
			)
			(layer "B.Fab")
		)
		(pad "1" smd rect
			(at 0.2667 0 90)
			(size 0.3048 0.381)
			(layers "B.Cu" "B.Mask" "B.Paste")
			(net "P0V9_CPU1_RT3_2A")
		)
		(pad "2" smd rect
			(at -0.2667 0 90)
			(size 0.3048 0.381)
			(layers "B.Cu" "B.Mask" "B.Paste")
			(net "GND")
		)
	)
	(footprint ""
		(layer "B.Cu")
		(at 184.1246 -355.052884 -90)
		(property "Reference" "PC517_1"
			(at 0 0 90)
			(layer "B.SilkS")
			(hide yes)
			(effects
				(font
					(size 1.27 1.27)
				)
				(justify mirror)
			)
		)
		(property "Value" ""
			(at 0 0 90)
			(layer "B.Fab")
			(effects
				(font
					(size 1.27 1.27)
				)
				(justify mirror)
			)
		)
		(duplicate_pad_numbers_are_jumpers no)
		(fp_line
			(start -1.524 0.762)
			(end 1.524 0.762)
			(stroke
				(width 0.1524)
				(type default)
			)
			(layer "B.SilkS")
		)
		(fp_line
			(start 1.524 0.762)
			(end 1.524 -0.762)
			(stroke
				(width 0.1524)
				(type default)
			)
			(layer "B.SilkS")
		)
		(fp_line
			(start -1.524 -0.762)
			(end -1.524 0.762)
			(stroke
				(width 0.1524)
				(type default)
			)
			(layer "B.SilkS")
		)
		(fp_line
			(start 1.524 -0.762)
			(end -1.524 -0.762)
			(stroke
				(width 0.1524)
				(type default)
			)
			(layer "B.SilkS")
		)
		(fp_line
			(start -1.1049 0.724916)
			(end -1.1049 -0.724916)
			(stroke
				(width 0.1)
				(type default)
			)
			(layer "B.Fab")
		)
		(fp_line
			(start 1.1049 0.724916)
			(end -1.1049 0.724916)
			(stroke
				(width 0.1)
				(type default)
			)
			(layer "B.Fab")
		)
		(fp_line
			(start -1.1049 -0.724916)
			(end 1.1049 -0.724916)
			(stroke
				(width 0.1)
				(type default)
			)
			(layer "B.Fab")
		)
		(fp_line
			(start 1.1049 -0.724916)
			(end 1.1049 0.724916)
			(stroke
				(width 0.1)
				(type default)
			)
			(layer "B.Fab")
		)
		(pad "1" smd rect
			(at 0.889 0 270)
			(size 1.016 1.27)
			(layers "B.Cu" "B.Mask" "B.Paste")
			(net "SW_P12V_AUX_PVDD11_S3_P1_FLT")
		)
		(pad "2" smd rect
			(at -0.889 0 270)
			(size 1.016 1.27)
			(layers "B.Cu" "B.Mask" "B.Paste")
			(net "GND")
		)
	)
	(footprint ""
		(layer "B.Cu")
		(at 185.801 -100.294948 -90)
		(property "Reference" "R958"
			(at 0 0 90)
			(layer "B.SilkS")
			(hide yes)
			(effects
				(font
					(size 1.27 1.27)
				)
				(justify mirror)
			)
		)
		(property "Value" ""
			(at 0 0 90)
			(layer "B.Fab")
			(effects
				(font
					(size 1.27 1.27)
				)
				(justify mirror)
			)
		)
		(duplicate_pad_numbers_are_jumpers no)
		(fp_line
			(start -0.7874 0.4064)
			(end 0.7874 0.4064)
			(stroke
				(width 0.1524)
				(type default)
			)
			(layer "B.SilkS")
		)
		(fp_line
			(start 0.7874 0.4064)
			(end 0.7874 -0.4064)
			(stroke
				(width 0.1524)
				(type default)
			)
			(layer "B.SilkS")
		)
		(fp_line
			(start -0.7874 -0.4064)
			(end -0.7874 0.4064)
			(stroke
				(width 0.1524)
				(type default)
			)
			(layer "B.SilkS")
		)
		(fp_line
			(start 0.7874 -0.4064)
			(end -0.7874 -0.4064)
			(stroke
				(width 0.1524)
				(type default)
			)
			(layer "B.SilkS")
		)
		(fp_line
			(start -0.67945 0.3048)
			(end -0.120396 0.3048)
			(stroke
				(width 0.1)
				(type default)
			)
			(layer "B.Fab")
		)
		(fp_line
			(start -0.120396 0.3048)
			(end -0.120396 0.2794)
			(stroke
				(width 0.1)
				(type default)
			)
			(layer "B.Fab")
		)
		(fp_line
			(start 0.12065 0.3048)
			(end 0.67945 0.3048)
			(stroke
				(width 0.1)
				(type default)
			)
			(layer "B.Fab")
		)
		(fp_line
			(start 0.67945 0.3048)
			(end 0.67945 -0.305054)
			(stroke
				(width 0.1)
				(type default)
			)
			(layer "B.Fab")
		)
		(fp_line
			(start -0.120396 0.2794)
			(end 0.12065 0.2794)
			(stroke
				(width 0.1)
				(type default)
			)
			(layer "B.Fab")
		)
		(fp_line
			(start 0.12065 0.2794)
			(end 0.12065 0.3048)
			(stroke
				(width 0.1)
				(type default)
			)
			(layer "B.Fab")
		)
		(fp_line
			(start -0.12065 -0.2794)
			(end -0.12065 -0.3048)
			(stroke
				(width 0.1)
				(type default)
			)
			(layer "B.Fab")
		)
		(fp_line
			(start 0.12065 -0.2794)
			(end -0.12065 -0.2794)
			(stroke
				(width 0.1)
				(type default)
			)
			(layer "B.Fab")
		)
		(fp_line
			(start -0.67945 -0.3048)
			(end -0.67945 0.3048)
			(stroke
				(width 0.1)
				(type default)
			)
			(layer "B.Fab")
		)
		(fp_line
			(start -0.12065 -0.3048)
			(end -0.67945 -0.3048)
			(stroke
				(width 0.1)
				(type default)
			)
			(layer "B.Fab")
		)
		(fp_line
			(start 0.12065 -0.305054)
			(end 0.12065 -0.2794)
			(stroke
				(width 0.1)
				(type default)
			)
			(layer "B.Fab")
		)
		(fp_line
			(start 0.67945 -0.305054)
			(end 0.12065 -0.305054)
			(stroke
				(width 0.1)
				(type default)
			)
			(layer "B.Fab")
		)
		(pad "1" smd circle
			(at 0.40005 0 90)
			(size 0 0)
			(layers "B.Cu" "B.Mask" "B.Paste")
			(net "FM_PLD_OCP_SFF_AUX_PWR_EN")
		)
		(pad "2" smd circle
			(at -0.40005 0 90)
			(size 0 0)
			(layers "B.Cu" "B.Mask" "B.Paste")
			(net "FM_PLD_OCP_SFF_AUX_PWR_R_EN")
		)
	)
	(footprint ""
		(layer "B.Cu")
		(at 339.518752 -398.942052 90)
		(property "Reference" "C626"
			(at 0 0 90)
			(layer "B.SilkS")
			(hide yes)
			(effects
				(font
					(size 1.27 1.27)
				)
				(justify mirror)
			)
		)
		(property "Value" ""
			(at 0 0 90)
			(layer "B.Fab")
			(effects
				(font
					(size 1.27 1.27)
				)
				(justify mirror)
			)
		)
		(duplicate_pad_numbers_are_jumpers no)
		(fp_line
			(start 0.7874 -0.4064)
			(end -0.7874 -0.4064)
			(stroke
				(width 0.1524)
				(type default)
			)
			(layer "B.SilkS")
		)
		(fp_line
			(start -0.7874 -0.4064)
			(end -0.7874 0.4064)
			(stroke
				(width 0.1524)
				(type default)
			)
			(layer "B.SilkS")
		)
		(fp_line
			(start 0.7874 0.4064)
			(end 0.7874 -0.4064)
			(stroke
				(width 0.1524)
				(type default)
			)
			(layer "B.SilkS")
		)
		(fp_line
			(start -0.7874 0.4064)
			(end 0.7874 0.4064)
			(stroke
				(width 0.1524)
				(type default)
			)
			(layer "B.SilkS")
		)
		(fp_line
			(start 0.67945 -0.305054)
			(end 0.12065 -0.305054)
			(stroke
				(width 0.1)
				(type default)
			)
			(layer "B.Fab")
		)
		(fp_line
			(start 0.12065 -0.305054)
			(end 0.12065 -0.2794)
			(stroke
				(width 0.1)
				(type default)
			)
			(layer "B.Fab")
		)
		(fp_line
			(start -0.12065 -0.3048)
			(end -0.67945 -0.3048)
			(stroke
				(width 0.1)
				(type default)
			)
			(layer "B.Fab")
		)
		(fp_line
			(start -0.67945 -0.3048)
			(end -0.67945 0.3048)
			(stroke
				(width 0.1)
				(type default)
			)
			(layer "B.Fab")
		)
		(fp_line
			(start 0.12065 -0.2794)
			(end -0.12065 -0.2794)
			(stroke
				(width 0.1)
				(type default)
			)
			(layer "B.Fab")
		)
		(fp_line
			(start -0.12065 -0.2794)
			(end -0.12065 -0.3048)
			(stroke
				(width 0.1)
				(type default)
			)
			(layer "B.Fab")
		)
		(fp_line
			(start 0.12065 0.2794)
			(end 0.12065 0.3048)
			(stroke
				(width 0.1)
				(type default)
			)
			(layer "B.Fab")
		)
		(fp_line
			(start -0.120396 0.2794)
			(end 0.12065 0.2794)
			(stroke
				(width 0.1)
				(type default)
			)
			(layer "B.Fab")
		)
		(fp_line
			(start 0.67945 0.3048)
			(end 0.67945 -0.305054)
			(stroke
				(width 0.1)
				(type default)
			)
			(layer "B.Fab")
		)
		(fp_line
			(start 0.12065 0.3048)
			(end 0.67945 0.3048)
			(stroke
				(width 0.1)
				(type default)
			)
			(layer "B.Fab")
		)
		(fp_line
			(start -0.120396 0.3048)
			(end -0.120396 0.2794)
			(stroke
				(width 0.1)
				(type default)
			)
			(layer "B.Fab")
		)
		(fp_line
			(start -0.67945 0.3048)
			(end -0.120396 0.3048)
			(stroke
				(width 0.1)
				(type default)
			)
			(layer "B.Fab")
		)
		(pad "1" smd circle
			(at 0.40005 0 270)
			(size 0 0)
			(layers "B.Cu" "B.Mask" "B.Paste")
			(net "P0V9_CPU0_RT1_2A")
		)
		(pad "2" smd circle
			(at -0.40005 0 270)
			(size 0 0)
			(layers "B.Cu" "B.Mask" "B.Paste")
			(net "GND")
		)
	)
)
